FILE_TYPE = CONNECTIVITY;
{Allegro Design Entry HDL 17.4-2019 S026 (4007227) 1/17/2022}
"PAGE_NUMBER" = 90;
0"NC";
1"GND\g";
2"GND\g";
3"P3V3\g";
4"M_F_CPU0_SA_CB<7:0>";
5"M_F_CPU0_SB_CB<7:0>";
6"M_F_CPU0_SA_CA<6:0>";
7"M_F_CPU0_SB_CA<6:0>";
8"M_F_CPU0_SA_DQ<31:0>";
9"M_F_CPU0_SB_DQ<31:0>";
10"M_F_CPU0_SA_DQS_DN<9:0>";
11"M_F_CPU0_SA_DQS_DP<9:0>";
12"M_F_CPU0_SB_DQS_DP<9:0>";
13"M_F_CPU0_SB_DQS_DN<9:0>";
14"M_F_CPU0_ALERT_N";
15"I3C_SPD_DDRAF_CPU0_SCL";
16"I3C_SPD_DDRF_CPU0_SCL";
17"PWRGD_CHF_CPU0_DIMM";
18"I3C_SPD_DDRAF_CPU0_SDA";
19"I3C_SPD_DDRF_CPU0_SDA";
20"PD_CHF_CPU0_DIMM_SAA";
21"P3V3_AUX\g";
22"M_F_CPU0_SB_CB<0>";
23"M_F_CPU0_SB_CB<1>";
24"PWRGD_CHAF_CPU0";
25"M_F_CPU0_SB_DQ<26>";
26"M_F_CPU0_SB_DQ<28>";
27"M_F_CPU0_SB_DQ<30>";
28"M_F_CPU0_SB_CA<1>";
29"M_F_CPU0_SA_DQ<14>";
30"M_F_CPU0_SB_DQS_DP<9>";
31"M_F_CPU0_SB_DQS_DN<9>";
32"M_F_CPU0_SA_DQS_DP<9>";
33"M_F_CPU0_SA_DQS_DN<9>";
34"M_F_CPU0_SA_DQS_DP<8>";
35"M_F_CPU0_SA_DQS_DN<8>";
36"M_F_CPU0_SB_DQS_DN<7>";
37"M_F_CPU0_SA_DQS_DP<7>";
38"M_F_CPU0_SB_DQS_DP<6>";
39"M_F_CPU0_SB_DQS_DN<6>";
40"M_F_CPU0_SA_DQS_DN<6>";
41"M_F_CPU0_SB_DQS_DP<5>";
42"M_F_CPU0_SB_DQS_DN<5>";
43"M_F_CPU0_SA_DQS_DP<5>";
44"M_F_CPU0_SA_DQS_DN<5>";
45"M_F_CPU0_SB_DQS_DP<4>";
46"M_F_CPU0_SB_DQS_DN<4>";
47"M_F_CPU0_SA_DQS_DP<4>";
48"M_F_CPU0_SA_DQS_DN<4>";
49"M_F_CPU0_SB_DQS_DP<3>";
50"M_F_CPU0_SB_DQS_DN<3>";
51"M_F_CPU0_SA_DQS_DP<3>";
52"M_F_CPU0_SA_DQS_DN<3>";
53"M_F_CPU0_SB_DQS_DP<2>";
54"M_F_CPU0_SB_DQS_DN<2>";
55"M_F_CPU0_SA_DQS_DP<2>";
56"M_F_CPU0_SA_DQS_DN<2>";
57"M_F_CPU0_SB_DQS_DP<1>";
58"M_F_CPU0_SB_DQS_DN<1>";
59"M_F_CPU0_SA_DQS_DP<1>";
60"M_F_CPU0_SA_DQS_DN<1>";
61"M_F_CPU0_SB_DQS_DP<0>";
62"M_F_CPU0_SB_DQS_DN<0>";
63"M_F_CPU0_SA_DQS_DP<0>";
64"M_F_CPU0_SA_DQS_DN<0>";
65"M_F_CPU0_SB_DQS_DP<7>";
66"M_F_CPU0_SB_DQS_DN<8>";
67"M_F_CPU0_SB_DQS_DP<8>";
68"M_F_CPU0_SA_DQS_DP<6>";
69"M_F_CPU0_SA_DQS_DN<7>";
70"M_F_CPU0_SA_DQ<22>";
71"M_F_CPU0_SB_PAR";
72"M_F_CPU0_SA_PAR";
73"M_F_CPU0_SA_CA<5>";
74"M_F_CPU0_SA_CA<6>";
75"M_F_CPU0_SA_DQ<28>";
76"M_F_CPU0_SA_DQ<31>";
77"M_F_CPU0_SB_RSP<0>";
78"M_F_CPU0_SA_RSP<0>";
79"M_F_CPU0_SB_DQ<0>";
80"M_F_CPU0_SB_DQ<1>";
81"M_F_CPU0_SB_DQ<2>";
82"M_F_CPU0_SB_DQ<3>";
83"M_F_CPU0_SB_DQ<4>";
84"M_F_CPU0_SB_DQ<5>";
85"M_F_CPU0_SB_DQ<6>";
86"M_F_CPU0_SB_DQ<7>";
87"M_F_CPU0_SB_DQ<8>";
88"M_F_CPU0_SB_DQ<9>";
89"M_F_CPU0_SB_DQ<10>";
90"M_F_CPU0_SB_DQ<11>";
91"M_F_CPU0_SB_DQ<12>";
92"M_F_CPU0_SB_DQ<13>";
93"M_F_CPU0_SB_DQ<14>";
94"M_F_CPU0_SB_DQ<15>";
95"M_F_CPU0_SB_DQ<16>";
96"M_F_CPU0_SB_DQ<17>";
97"M_F_CPU0_SB_DQ<18>";
98"M_F_CPU0_SB_DQ<19>";
99"M_F_CPU0_SB_DQ<20>";
100"M_F_CPU0_SB_DQ<21>";
101"M_F_CPU0_SB_DQ<22>";
102"M_F_CPU0_SB_DQ<23>";
103"M_F_CPU0_SB_DQ<24>";
104"M_F_CPU0_SB_DQ<25>";
105"M_F_CPU0_SB_DQ<27>";
106"M_F_CPU0_SB_DQ<29>";
107"M_F_CPU0_SB_DQ<31>";
108"M_F_CPU0_SA_DQ<0>";
109"M_F_CPU0_SA_DQ<1>";
110"M_F_CPU0_SA_DQ<2>";
111"M_F_CPU0_SA_DQ<3>";
112"M_F_CPU0_SA_DQ<4>";
113"M_F_CPU0_SA_DQ<5>";
114"M_F_CPU0_SA_DQ<6>";
115"M_F_CPU0_SA_DQ<7>";
116"M_F_CPU0_SA_DQ<8>";
117"M_F_CPU0_SA_DQ<9>";
118"M_F_CPU0_SA_DQ<10>";
119"M_F_CPU0_SA_DQ<11>";
120"M_F_CPU0_SA_DQ<12>";
121"M_F_CPU0_SA_DQ<13>";
122"M_F_CPU0_SA_DQ<15>";
123"M_F_CPU0_SA_DQ<16>";
124"M_F_CPU0_SA_DQ<17>";
125"M_F_CPU0_SA_DQ<18>";
126"M_F_CPU0_SA_DQ<19>";
127"M_F_CPU0_SA_DQ<20>";
128"M_F_CPU0_SA_DQ<21>";
129"M_F_CPU0_SA_DQ<23>";
130"M_F_CPU0_SA_DQ<24>";
131"M_F_CPU0_SA_DQ<25>";
132"M_F_CPU0_SA_DQ<26>";
133"M_F_CPU0_SA_DQ<27>";
134"M_F_CPU0_SA_DQ<29>";
135"M_F_CPU0_SA_DQ<30>";
136"M_F_CPU0_SB_CS_N<1>";
137"M_F_CPU0_SA_CS_N<1>";
138"M_F_CPU0_SB_CS_N<0>";
139"M_F_CPU0_SA_CS_N<0>";
140"M_F_CPU0_CLK_DP<0>";
141"M_F_CPU0_CLK_DN<0>";
142"M_F_CPU0_SB_CB<2>";
143"M_F_CPU0_SB_CB<3>";
144"M_F_CPU0_SB_CB<4>";
145"M_F_CPU0_SB_CB<5>";
146"M_F_CPU0_SB_CB<6>";
147"M_F_CPU0_SA_CB<2>";
148"M_F_CPU0_SA_CB<3>";
149"M_F_CPU0_SA_CB<6>";
150"M_F_CPU0_SB_CA<6>";
151"M_F_CPU0_SB_CA<5>";
152"M_F_CPU0_SB_CA<4>";
153"M_F_CPU0_SA_CA<4>";
154"M_F_CPU0_SB_CA<3>";
155"M_F_CPU0_SA_CA<3>";
156"M_F_CPU0_SB_CA<2>";
157"M_F_CPU0_SA_CA<2>";
158"M_F_CPU0_SA_CA<1>";
159"M_F_CPU0_SB_CA<0>";
160"M_F_CPU0_SA_CA<0>";
161"M_F_CPU0_SB_CB<7>";
162"M_F_CPU0_SA_CB<7>";
163"PD_CHF_CPU0_DIMM_SAA";
164"M_F_CPU0_SA_CB<5>";
165"M_F_CPU0_SA_CB<4>";
166"M_F_CPU0_SA_CB<1>";
167"M_F_CPU0_SA_CB<0>";
168"M_F_CPU0_RESET_N";
169"GND\g";
170"GND\g";
171"GND\g";
172"P12V_MEM_CPU0\g";
%"GND"
"1","(-2225,2175)","0","mstr_symbols","I150";
;
VOLTAGE"0.0"
CDS_LIB"mstr_symbols"
SIZE"1B"
BODY_TYPE"PLUMBING"
HDL_POWER"GND";
"A\NAC"169;
%"GND"
"1","(-425,1950)","0","mstr_symbols","I152";
;
VOLTAGE"0.0"
SIZE"1B"
CDS_LIB"mstr_symbols"
BODY_TYPE"PLUMBING"
HDL_POWER"GND";
"A\NAC"170;
%"VCC_CORE"
"1","(-8550,3775)","0","mstr_symbols","I175";
;
HDL_POWER"P3V3_AUX"
ROOM"PVCCINFAON_CPU0_CTRL"
VOLTAGE"3.3"
CDS_LIB"mstr_symbols";
"A"21;
%"TAP"
"1","(-7775,3525)","2","mstr_standard","I177";
;
CDS_LIB"mstr_standard"
BODY_TYPE"PLUMBING"
HDL_TAP"TRUE";
"B \NAC \NWC"5;
"S \NAC"
BN"0"22;
%"TAP"
"1","(-7775,3575)","2","mstr_standard","I178";
;
CDS_LIB"mstr_standard"
BODY_TYPE"PLUMBING"
HDL_TAP"TRUE";
"B \NAC \NWC"5;
"S \NAC"
BN"1"23;
%"TAP"
"1","(-7775,3625)","2","mstr_standard","I179";
;
CDS_LIB"mstr_standard"
BODY_TYPE"PLUMBING"
HDL_TAP"TRUE";
"B \NAC \NWC"5;
"S \NAC"
BN"2"142;
%"TAP"
"1","(-7775,3725)","2","mstr_standard","I192";
;
CDS_LIB"mstr_standard"
BODY_TYPE"PLUMBING"
HDL_TAP"TRUE";
"B \NAC \NWC"5;
"S \NAC"
BN"4"144;
%"TAP"
"1","(-7775,3675)","2","mstr_standard","I193";
;
CDS_LIB"mstr_standard"
BODY_TYPE"PLUMBING"
HDL_TAP"TRUE";
"B \NAC \NWC"5;
"S \NAC"
BN"3"143;
%"TAP"
"1","(-7775,3775)","2","mstr_standard","I194";
;
CDS_LIB"mstr_standard"
BODY_TYPE"PLUMBING"
HDL_TAP"TRUE";
"B \NAC \NWC"5;
"S \NAC"
BN"5"145;
%"TAP"
"1","(-7775,3825)","2","mstr_standard","I195";
;
CDS_LIB"mstr_standard"
BODY_TYPE"PLUMBING"
HDL_TAP"TRUE";
"B \NAC \NWC"5;
"S \NAC"
BN"6"146;
%"TAP"
"1","(-7775,3875)","2","mstr_standard","I196";
;
CDS_LIB"mstr_standard"
BODY_TYPE"PLUMBING"
HDL_TAP"TRUE";
"B \NAC \NWC"5;
"S \NAC"
BN"7"161;
%"TAP"
"1","(-7775,3975)","2","mstr_standard","I197";
;
CDS_LIB"mstr_standard"
BODY_TYPE"PLUMBING"
HDL_TAP"TRUE";
"B \NAC \NWC"4;
"S \NAC"
BN"0"167;
%"TAP"
"1","(-7775,4025)","2","mstr_standard","I198";
;
CDS_LIB"mstr_standard"
BODY_TYPE"PLUMBING"
HDL_TAP"TRUE";
"B \NAC \NWC"4;
"S \NAC"
BN"1"166;
%"TAP"
"1","(-7775,4075)","2","mstr_standard","I199";
;
CDS_LIB"mstr_standard"
BODY_TYPE"PLUMBING"
HDL_TAP"TRUE";
"B \NAC \NWC"4;
"S \NAC"
BN"2"147;
%"TAP"
"1","(-7775,4125)","2","mstr_standard","I200";
;
CDS_LIB"mstr_standard"
BODY_TYPE"PLUMBING"
HDL_TAP"TRUE";
"B \NAC \NWC"4;
"S \NAC"
BN"3"148;
%"TAP"
"1","(-7775,4225)","2","mstr_standard","I201";
;
CDS_LIB"mstr_standard"
BODY_TYPE"PLUMBING"
HDL_TAP"TRUE";
"B \NAC \NWC"4;
"S \NAC"
BN"5"164;
%"TAP"
"1","(-7775,4175)","2","mstr_standard","I202";
;
CDS_LIB"mstr_standard"
BODY_TYPE"PLUMBING"
HDL_TAP"TRUE";
"B \NAC \NWC"4;
"S \NAC"
BN"4"165;
%"TAP"
"1","(-7775,4325)","2","mstr_standard","I203";
;
CDS_LIB"mstr_standard"
BODY_TYPE"PLUMBING"
HDL_TAP"TRUE";
"B \NAC \NWC"4;
"S \NAC"
BN"7"162;
%"TAP"
"1","(-7775,4275)","2","mstr_standard","I204";
;
CDS_LIB"mstr_standard"
BODY_TYPE"PLUMBING"
HDL_TAP"TRUE";
"B \NAC \NWC"4;
"S \NAC"
BN"6"149;
%"TAP"
"1","(-7775,5025)","2","mstr_standard","I205";
;
CDS_LIB"mstr_standard"
BODY_TYPE"PLUMBING"
HDL_TAP"TRUE";
"B \NAC \NWC"7;
"S \NAC"
BN"0"159;
%"TAP"
"1","(-7775,5125)","2","mstr_standard","I206";
;
CDS_LIB"mstr_standard"
BODY_TYPE"PLUMBING"
HDL_TAP"TRUE";
"B \NAC \NWC"7;
"S \NAC"
BN"2"156;
%"TAP"
"1","(-7775,5075)","2","mstr_standard","I207";
;
CDS_LIB"mstr_standard"
BODY_TYPE"PLUMBING"
HDL_TAP"TRUE";
"B \NAC \NWC"7;
"S \NAC"
BN"1"28;
%"TAP"
"1","(-7775,5225)","2","mstr_standard","I208";
;
CDS_LIB"mstr_standard"
BODY_TYPE"PLUMBING"
HDL_TAP"TRUE";
"B \NAC \NWC"7;
"S \NAC"
BN"4"152;
%"TAP"
"1","(-7775,5175)","2","mstr_standard","I209";
;
CDS_LIB"mstr_standard"
BODY_TYPE"PLUMBING"
HDL_TAP"TRUE";
"B \NAC \NWC"7;
"S \NAC"
BN"3"154;
%"TAP"
"1","(-7775,5275)","2","mstr_standard","I210";
;
CDS_LIB"mstr_standard"
BODY_TYPE"PLUMBING"
HDL_TAP"TRUE";
"B \NAC \NWC"7;
"S \NAC"
BN"5"151;
%"TAP"
"1","(-7775,5325)","2","mstr_standard","I211";
;
CDS_LIB"mstr_standard"
BODY_TYPE"PLUMBING"
HDL_TAP"TRUE";
"B \NAC \NWC"7;
"S \NAC"
BN"6"150;
%"TAP"
"1","(-7775,5425)","2","mstr_standard","I212";
;
CDS_LIB"mstr_standard"
BODY_TYPE"PLUMBING"
HDL_TAP"TRUE";
"B \NAC \NWC"6;
"S \NAC"
BN"0"160;
%"TAP"
"1","(-7775,5475)","2","mstr_standard","I213";
;
CDS_LIB"mstr_standard"
BODY_TYPE"PLUMBING"
HDL_TAP"TRUE";
"B \NAC \NWC"6;
"S \NAC"
BN"1"158;
%"TAP"
"1","(-7775,5525)","2","mstr_standard","I214";
;
CDS_LIB"mstr_standard"
BODY_TYPE"PLUMBING"
HDL_TAP"TRUE";
"B \NAC \NWC"6;
"S \NAC"
BN"2"157;
%"TAP"
"1","(-7775,5625)","2","mstr_standard","I215";
;
CDS_LIB"mstr_standard"
BODY_TYPE"PLUMBING"
HDL_TAP"TRUE";
"B \NAC \NWC"6;
"S \NAC"
BN"4"153;
%"TAP"
"1","(-7775,5575)","2","mstr_standard","I216";
;
CDS_LIB"mstr_standard"
BODY_TYPE"PLUMBING"
HDL_TAP"TRUE";
"B \NAC \NWC"6;
"S \NAC"
BN"3"155;
%"TAP"
"1","(-7775,5675)","2","mstr_standard","I217";
;
CDS_LIB"mstr_standard"
BODY_TYPE"PLUMBING"
HDL_TAP"TRUE";
"B \NAC \NWC"6;
"S \NAC"
BN"5"73;
%"TAP"
"1","(-7775,5725)","2","mstr_standard","I218";
;
CDS_LIB"mstr_standard"
BODY_TYPE"PLUMBING"
HDL_TAP"TRUE";
"B \NAC \NWC"6;
"S \NAC"
BN"6"74;
%"TAP"
"1","(-6075,5625)","0","mstr_standard","I219";
;
CDS_LIB"mstr_standard"
BODY_TYPE"PLUMBING"
HDL_TAP"TRUE";
"B \NAC \NWC"8;
"S \NAC"
BN"29"134;
%"TAP"
"1","(-6075,5675)","0","mstr_standard","I220";
;
CDS_LIB"mstr_standard"
BODY_TYPE"PLUMBING"
HDL_TAP"TRUE";
"B \NAC \NWC"8;
"S \NAC"
BN"30"135;
%"TAP"
"1","(-6075,5575)","0","mstr_standard","I221";
;
CDS_LIB"mstr_standard"
BODY_TYPE"PLUMBING"
HDL_TAP"TRUE";
"B \NAC \NWC"8;
"S \NAC"
BN"28"75;
%"TAP"
"1","(-6075,5525)","0","mstr_standard","I222";
;
CDS_LIB"mstr_standard"
BODY_TYPE"PLUMBING"
HDL_TAP"TRUE";
"B \NAC \NWC"8;
"S \NAC"
BN"27"133;
%"TAP"
"1","(-6075,5725)","0","mstr_standard","I223";
;
CDS_LIB"mstr_standard"
BODY_TYPE"PLUMBING"
HDL_TAP"TRUE";
"B \NAC \NWC"8;
"S \NAC"
BN"31"76;
%"TAP"
"1","(-6075,5475)","0","mstr_standard","I224";
;
CDS_LIB"mstr_standard"
BODY_TYPE"PLUMBING"
HDL_TAP"TRUE";
"B \NAC \NWC"8;
"S \NAC"
BN"26"132;
%"TAP"
"1","(-6075,5425)","0","mstr_standard","I225";
;
CDS_LIB"mstr_standard"
BODY_TYPE"PLUMBING"
HDL_TAP"TRUE";
"B \NAC \NWC"8;
"S \NAC"
BN"25"131;
%"TAP"
"1","(-6075,5375)","0","mstr_standard","I226";
;
CDS_LIB"mstr_standard"
BODY_TYPE"PLUMBING"
HDL_TAP"TRUE";
"B \NAC \NWC"8;
"S \NAC"
BN"24"130;
%"TAP"
"1","(-6075,5275)","0","mstr_standard","I227";
;
CDS_LIB"mstr_standard"
BODY_TYPE"PLUMBING"
HDL_TAP"TRUE";
"B \NAC \NWC"8;
"S \NAC"
BN"22"70;
%"TAP"
"1","(-6075,5225)","0","mstr_standard","I228";
;
CDS_LIB"mstr_standard"
BODY_TYPE"PLUMBING"
HDL_TAP"TRUE";
"B \NAC \NWC"8;
"S \NAC"
BN"21"128;
%"TAP"
"1","(-6075,5325)","0","mstr_standard","I229";
;
CDS_LIB"mstr_standard"
BODY_TYPE"PLUMBING"
HDL_TAP"TRUE";
"B \NAC \NWC"8;
"S \NAC"
BN"23"129;
%"TAP"
"1","(-6075,5125)","0","mstr_standard","I230";
;
CDS_LIB"mstr_standard"
BODY_TYPE"PLUMBING"
HDL_TAP"TRUE";
"B \NAC \NWC"8;
"S \NAC"
BN"19"126;
%"TAP"
"1","(-6075,5175)","0","mstr_standard","I231";
;
CDS_LIB"mstr_standard"
BODY_TYPE"PLUMBING"
HDL_TAP"TRUE";
"B \NAC \NWC"8;
"S \NAC"
BN"20"127;
%"TAP"
"1","(-6075,4975)","0","mstr_standard","I232";
;
CDS_LIB"mstr_standard"
BODY_TYPE"PLUMBING"
HDL_TAP"TRUE";
"B \NAC \NWC"8;
"S \NAC"
BN"16"123;
%"TAP"
"1","(-6075,5075)","0","mstr_standard","I233";
;
CDS_LIB"mstr_standard"
BODY_TYPE"PLUMBING"
HDL_TAP"TRUE";
"B \NAC \NWC"8;
"S \NAC"
BN"18"125;
%"TAP"
"1","(-6075,5025)","0","mstr_standard","I234";
;
CDS_LIB"mstr_standard"
BODY_TYPE"PLUMBING"
HDL_TAP"TRUE";
"B \NAC \NWC"8;
"S \NAC"
BN"17"124;
%"TAP"
"1","(-6075,4725)","0","mstr_standard","I235";
;
CDS_LIB"mstr_standard"
BODY_TYPE"PLUMBING"
HDL_TAP"TRUE";
"B \NAC \NWC"8;
"S \NAC"
BN"11"119;
%"TAP"
"1","(-6075,4775)","0","mstr_standard","I236";
;
CDS_LIB"mstr_standard"
BODY_TYPE"PLUMBING"
HDL_TAP"TRUE";
"B \NAC \NWC"8;
"S \NAC"
BN"12"120;
%"TAP"
"1","(-6075,4825)","0","mstr_standard","I237";
;
CDS_LIB"mstr_standard"
BODY_TYPE"PLUMBING"
HDL_TAP"TRUE";
"B \NAC \NWC"8;
"S \NAC"
BN"13"121;
%"TAP"
"1","(-6075,4925)","0","mstr_standard","I238";
;
CDS_LIB"mstr_standard"
BODY_TYPE"PLUMBING"
HDL_TAP"TRUE";
"B \NAC \NWC"8;
"S \NAC"
BN"15"122;
%"TAP"
"1","(-6075,4875)","0","mstr_standard","I239";
;
CDS_LIB"mstr_standard"
BODY_TYPE"PLUMBING"
HDL_TAP"TRUE";
"B \NAC \NWC"8;
"S \NAC"
BN"14"29;
%"TAP"
"1","(-6075,4675)","0","mstr_standard","I240";
;
CDS_LIB"mstr_standard"
BODY_TYPE"PLUMBING"
HDL_TAP"TRUE";
"B \NAC \NWC"8;
"S \NAC"
BN"10"118;
%"TAP"
"1","(-6075,4625)","0","mstr_standard","I241";
;
CDS_LIB"mstr_standard"
BODY_TYPE"PLUMBING"
HDL_TAP"TRUE";
"B \NAC \NWC"8;
"S \NAC"
BN"9"117;
%"TAP"
"1","(-6075,4575)","0","mstr_standard","I242";
;
CDS_LIB"mstr_standard"
BODY_TYPE"PLUMBING"
HDL_TAP"TRUE";
"B \NAC \NWC"8;
"S \NAC"
BN"8"116;
%"TAP"
"1","(-6075,4475)","0","mstr_standard","I243";
;
CDS_LIB"mstr_standard"
BODY_TYPE"PLUMBING"
HDL_TAP"TRUE";
"B \NAC \NWC"8;
"S \NAC"
BN"6"114;
%"TAP"
"1","(-6075,4525)","0","mstr_standard","I244";
;
CDS_LIB"mstr_standard"
BODY_TYPE"PLUMBING"
HDL_TAP"TRUE";
"B \NAC \NWC"8;
"S \NAC"
BN"7"115;
%"TAP"
"1","(-6075,4425)","0","mstr_standard","I245";
;
CDS_LIB"mstr_standard"
BODY_TYPE"PLUMBING"
HDL_TAP"TRUE";
"B \NAC \NWC"8;
"S \NAC"
BN"5"113;
%"TAP"
"1","(-6075,4375)","0","mstr_standard","I246";
;
CDS_LIB"mstr_standard"
BODY_TYPE"PLUMBING"
HDL_TAP"TRUE";
"B \NAC \NWC"8;
"S \NAC"
BN"4"112;
%"TAP"
"1","(-6075,4325)","0","mstr_standard","I247";
;
CDS_LIB"mstr_standard"
BODY_TYPE"PLUMBING"
HDL_TAP"TRUE";
"B \NAC \NWC"8;
"S \NAC"
BN"3"111;
%"TAP"
"1","(-6075,4225)","0","mstr_standard","I248";
;
CDS_LIB"mstr_standard"
BODY_TYPE"PLUMBING"
HDL_TAP"TRUE";
"B \NAC \NWC"8;
"S \NAC"
BN"1"109;
%"TAP"
"1","(-6075,4275)","0","mstr_standard","I249";
;
CDS_LIB"mstr_standard"
BODY_TYPE"PLUMBING"
HDL_TAP"TRUE";
"B \NAC \NWC"8;
"S \NAC"
BN"2"110;
%"TAP"
"1","(-6075,3975)","0","mstr_standard","I250";
;
CDS_LIB"mstr_standard"
BODY_TYPE"PLUMBING"
HDL_TAP"TRUE";
"B \NAC \NWC"9;
"S \NAC"
BN"29"106;
%"TAP"
"1","(-6075,4075)","0","mstr_standard","I251";
;
CDS_LIB"mstr_standard"
BODY_TYPE"PLUMBING"
HDL_TAP"TRUE";
"B \NAC \NWC"9;
"S \NAC"
BN"31"107;
%"TAP"
"1","(-6075,4025)","0","mstr_standard","I252";
;
CDS_LIB"mstr_standard"
BODY_TYPE"PLUMBING"
HDL_TAP"TRUE";
"B \NAC \NWC"9;
"S \NAC"
BN"30"27;
%"TAP"
"1","(-6075,4175)","0","mstr_standard","I253";
;
CDS_LIB"mstr_standard"
BODY_TYPE"PLUMBING"
HDL_TAP"TRUE";
"B \NAC \NWC"8;
"S \NAC"
BN"0"108;
%"TAP"
"1","(-6075,3725)","0","mstr_standard","I254";
;
CDS_LIB"mstr_standard"
BODY_TYPE"PLUMBING"
HDL_TAP"TRUE";
"B \NAC \NWC"9;
"S \NAC"
BN"24"103;
%"TAP"
"1","(-6075,3925)","0","mstr_standard","I255";
;
CDS_LIB"mstr_standard"
BODY_TYPE"PLUMBING"
HDL_TAP"TRUE";
"B \NAC \NWC"9;
"S \NAC"
BN"28"26;
%"TAP"
"1","(-6075,3775)","0","mstr_standard","I256";
;
CDS_LIB"mstr_standard"
BODY_TYPE"PLUMBING"
HDL_TAP"TRUE";
"B \NAC \NWC"9;
"S \NAC"
BN"25"104;
%"TAP"
"1","(-6075,3875)","0","mstr_standard","I257";
;
CDS_LIB"mstr_standard"
BODY_TYPE"PLUMBING"
HDL_TAP"TRUE";
"B \NAC \NWC"9;
"S \NAC"
BN"27"105;
%"TAP"
"1","(-6075,3825)","0","mstr_standard","I258";
;
CDS_LIB"mstr_standard"
BODY_TYPE"PLUMBING"
HDL_TAP"TRUE";
"B \NAC \NWC"9;
"S \NAC"
BN"26"25;
%"TAP"
"1","(-6075,3475)","0","mstr_standard","I259";
;
CDS_LIB"mstr_standard"
BODY_TYPE"PLUMBING"
HDL_TAP"TRUE";
"B \NAC \NWC"9;
"S \NAC"
BN"19"98;
%"TAP"
"1","(-6075,3675)","0","mstr_standard","I260";
;
CDS_LIB"mstr_standard"
BODY_TYPE"PLUMBING"
HDL_TAP"TRUE";
"B \NAC \NWC"9;
"S \NAC"
BN"23"102;
%"TAP"
"1","(-6075,3525)","0","mstr_standard","I261";
;
CDS_LIB"mstr_standard"
BODY_TYPE"PLUMBING"
HDL_TAP"TRUE";
"B \NAC \NWC"9;
"S \NAC"
BN"20"99;
%"TAP"
"1","(-6075,3625)","0","mstr_standard","I262";
;
CDS_LIB"mstr_standard"
BODY_TYPE"PLUMBING"
HDL_TAP"TRUE";
"B \NAC \NWC"9;
"S \NAC"
BN"22"101;
%"TAP"
"1","(-6075,3575)","0","mstr_standard","I263";
;
CDS_LIB"mstr_standard"
BODY_TYPE"PLUMBING"
HDL_TAP"TRUE";
"B \NAC \NWC"9;
"S \NAC"
BN"21"100;
%"TAP"
"1","(-6075,3325)","0","mstr_standard","I264";
;
CDS_LIB"mstr_standard"
BODY_TYPE"PLUMBING"
HDL_TAP"TRUE";
"B \NAC \NWC"9;
"S \NAC"
BN"16"95;
%"TAP"
"1","(-6075,3375)","0","mstr_standard","I265";
;
CDS_LIB"mstr_standard"
BODY_TYPE"PLUMBING"
HDL_TAP"TRUE";
"B \NAC \NWC"9;
"S \NAC"
BN"17"96;
%"TAP"
"1","(-6075,3425)","0","mstr_standard","I266";
;
CDS_LIB"mstr_standard"
BODY_TYPE"PLUMBING"
HDL_TAP"TRUE";
"B \NAC \NWC"9;
"S \NAC"
BN"18"97;
%"TAP"
"1","(-6075,3225)","0","mstr_standard","I267";
;
CDS_LIB"mstr_standard"
BODY_TYPE"PLUMBING"
HDL_TAP"TRUE";
"B \NAC \NWC"9;
"S \NAC"
BN"14"93;
%"TAP"
"1","(-6075,3275)","0","mstr_standard","I268";
;
CDS_LIB"mstr_standard"
BODY_TYPE"PLUMBING"
HDL_TAP"TRUE";
"B \NAC \NWC"9;
"S \NAC"
BN"15"94;
%"TAP"
"1","(-6075,3175)","0","mstr_standard","I269";
;
CDS_LIB"mstr_standard"
BODY_TYPE"PLUMBING"
HDL_TAP"TRUE";
"B \NAC \NWC"9;
"S \NAC"
BN"13"92;
%"TAP"
"1","(-6075,3125)","0","mstr_standard","I270";
;
CDS_LIB"mstr_standard"
BODY_TYPE"PLUMBING"
HDL_TAP"TRUE";
"B \NAC \NWC"9;
"S \NAC"
BN"12"91;
%"TAP"
"1","(-6075,3075)","0","mstr_standard","I271";
;
CDS_LIB"mstr_standard"
BODY_TYPE"PLUMBING"
HDL_TAP"TRUE";
"B \NAC \NWC"9;
"S \NAC"
BN"11"90;
%"TAP"
"1","(-6075,3025)","0","mstr_standard","I272";
;
CDS_LIB"mstr_standard"
BODY_TYPE"PLUMBING"
HDL_TAP"TRUE";
"B \NAC \NWC"9;
"S \NAC"
BN"10"89;
%"TAP"
"1","(-6075,2975)","0","mstr_standard","I273";
;
CDS_LIB"mstr_standard"
BODY_TYPE"PLUMBING"
HDL_TAP"TRUE";
"B \NAC \NWC"9;
"S \NAC"
BN"9"88;
%"TAP"
"1","(-6075,2925)","0","mstr_standard","I274";
;
CDS_LIB"mstr_standard"
BODY_TYPE"PLUMBING"
HDL_TAP"TRUE";
"B \NAC \NWC"9;
"S \NAC"
BN"8"87;
%"TAP"
"1","(-6075,2825)","0","mstr_standard","I275";
;
CDS_LIB"mstr_standard"
BODY_TYPE"PLUMBING"
HDL_TAP"TRUE";
"B \NAC \NWC"9;
"S \NAC"
BN"6"85;
%"TAP"
"1","(-6075,2875)","0","mstr_standard","I276";
;
CDS_LIB"mstr_standard"
BODY_TYPE"PLUMBING"
HDL_TAP"TRUE";
"B \NAC \NWC"9;
"S \NAC"
BN"7"86;
%"TAP"
"1","(-6075,2775)","0","mstr_standard","I277";
;
CDS_LIB"mstr_standard"
BODY_TYPE"PLUMBING"
HDL_TAP"TRUE";
"B \NAC \NWC"9;
"S \NAC"
BN"5"84;
%"TAP"
"1","(-6075,2725)","0","mstr_standard","I278";
;
CDS_LIB"mstr_standard"
BODY_TYPE"PLUMBING"
HDL_TAP"TRUE";
"B \NAC \NWC"9;
"S \NAC"
BN"4"83;
%"TAP"
"1","(-6075,2675)","0","mstr_standard","I279";
;
CDS_LIB"mstr_standard"
BODY_TYPE"PLUMBING"
HDL_TAP"TRUE";
"B \NAC \NWC"9;
"S \NAC"
BN"3"82;
%"TAP"
"1","(-6075,2625)","0","mstr_standard","I280";
;
CDS_LIB"mstr_standard"
BODY_TYPE"PLUMBING"
HDL_TAP"TRUE";
"B \NAC \NWC"9;
"S \NAC"
BN"2"81;
%"TAP"
"1","(-6075,2525)","0","mstr_standard","I281";
;
CDS_LIB"mstr_standard"
BODY_TYPE"PLUMBING"
HDL_TAP"TRUE";
"B \NAC \NWC"9;
"S \NAC"
BN"0"79;
%"TAP"
"1","(-6075,2575)","0","mstr_standard","I282";
;
CDS_LIB"mstr_standard"
BODY_TYPE"PLUMBING"
HDL_TAP"TRUE";
"B \NAC \NWC"9;
"S \NAC"
BN"1"80;
%"GND"
"1","(-6400,1375)","0","mstr_symbols","I332";
;
VOLTAGE"0.0"
BOM_COST"MEM"
CDS_LIB"mstr_symbols"
SIZE"1B"
BODY_TYPE"PLUMBING"
HDL_POWER"GND";
"A\NAC"1;
%"Q_RES"
"2","(-6400,1600)","0","pure_quanta","I349";
;
LOCATION"R764"
$SEC"1"
CDS_SEC"1"
PACK_TYPE"0402LF"
VALUE"84.5K"
TOLERANCE"1%"
MATERIAL"CHIP"
WATTAGE"1/16W"
CDS_LIB"pure_quanta"
PART_NUMBER"CS38452FB05";
"A"
$PN"1"163;
"B"
$PN"2"1;
%"SCONN288_DDR506112002KQ"
"1","(-6925,3975)","0","pure_quanta","I350";
;
LOCATION"J23"
$SEC"1"
CDS_SEC"1"
MATERIAL"IO"
PART_TYPE"SMLF"
VALUE"SCONN288_DDR506112002KQ"
CDS_LIB"pure_quanta"
NEEDS_NO_SIZE"TRUE"
CDS_LMAN_SYM_OUTLINE"-450,1900,450,-1850"
PART_NUMBER"DFHST8FS479";
"PWR_GOOD||FAIL_N"
$PN"147"17;
"DQ31_A"
$PN"194"76;
"CB7_A"
$PN"205"162;
"CB4_A"
$PN"58"165;
"CB1_A"
$PN"53"166;
"CB7_B"
$PN"236"161;
"ALERT_N \B"
$PN"62"14;
"CA0_A"
$PN"66"160;
"CA0_B"
$PN"76"159;
"CA1_A"
$PN"211"158;
"CA1_B"
$PN"221"28;
"CA2_A"
$PN"68"157;
"CA2_B"
$PN"78"156;
"CA3_A"
$PN"213"155;
"CA3_B"
$PN"223"154;
"CA4_A"
$PN"70"153;
"CA4_B"
$PN"80"152;
"CA5_A"
$PN"215"73;
"CA5_B"
$PN"225"151;
"CA6_A"
$PN"72"74;
"CA6_B"
$PN"82"150;
"CB6_A"
$PN"203"149;
"CB5_A"
$PN"60"164;
"CB3_A"
$PN"198"148;
"CB2_A"
$PN"196"147;
"CB0_A"
$PN"51"167;
"CB6_B"
$PN"234"146;
"CB5_B"
$PN"91"145;
"CB4_B"
$PN"89"144;
"CB3_B"
$PN"243"143;
"CB2_B"
$PN"241"142;
"CB1_B"
$PN"98"23;
"CB0_B"
$PN"96"22;
"CK_C \B"
$PN"218"141;
"CK_T"
$PN"217"140;
"CS0_A_N"
$PN"64"139;
"CS0_B_N"
$PN"84"138;
"CS1_A_N"
$PN"209"137;
"CS1_B_N"
$PN"229"136;
"DQ30_A"
$PN"192"135;
"DQ29_A"
$PN"49"134;
"DQ28_A"
$PN"47"75;
"DQ27_A"
$PN"187"133;
"DQ26_A"
$PN"185"132;
"DQ25_A"
$PN"42"131;
"DQ24_A"
$PN"40"130;
"DQ23_A"
$PN"183"129;
"DQ22_A"
$PN"181"70;
"DQ21_A"
$PN"38"128;
"DQ20_A"
$PN"36"127;
"DQ19_A"
$PN"176"126;
"DQ18_A"
$PN"174"125;
"DQ17_A"
$PN"31"124;
"DQ16_A"
$PN"29"123;
"DQ15_A"
$PN"172"122;
"DQ14_A"
$PN"170"29;
"DQ13_A"
$PN"27"121;
"DQ12_A"
$PN"25"120;
"DQ11_A"
$PN"165"119;
"DQ10_A"
$PN"163"118;
"DQ9_A"
$PN"20"117;
"DQ8_A"
$PN"18"116;
"DQ7_A"
$PN"161"115;
"DQ6_A"
$PN"159"114;
"DQ5_A"
$PN"16"113;
"DQ4_A"
$PN"14"112;
"DQ3_A"
$PN"154"111;
"DQ2_A"
$PN"152"110;
"DQ1_A"
$PN"9"109;
"DQ0_A"
$PN"7"108;
"DQ31_B"
$PN"287"107;
"DQ30_B"
$PN"285"27;
"DQ29_B"
$PN"142"106;
"DQ28_B"
$PN"140"26;
"DQ27_B"
$PN"280"105;
"DQ26_B"
$PN"278"25;
"DQ25_B"
$PN"135"104;
"DQ24_B"
$PN"133"103;
"DQ23_B"
$PN"276"102;
"DQ22_B"
$PN"274"101;
"DQ21_B"
$PN"131"100;
"DQ20_B"
$PN"129"99;
"DQ19_B"
$PN"269"98;
"DQ18_B"
$PN"267"97;
"DQ17_B"
$PN"124"96;
"DQ16_B"
$PN"122"95;
"DQ15_B"
$PN"265"94;
"DQ14_B"
$PN"263"93;
"DQ13_B"
$PN"120"92;
"DQ12_B"
$PN"118"91;
"DQ11_B"
$PN"258"90;
"DQ10_B"
$PN"256"89;
"DQ9_B"
$PN"113"88;
"DQ8_B"
$PN"111"87;
"DQ7_B"
$PN"254"86;
"DQ6_B"
$PN"252"85;
"DQ5_B"
$PN"109"84;
"DQ4_B"
$PN"107"83;
"DQ3_B"
$PN"247"82;
"DQ2_B"
$PN"245"81;
"DQ1_B"
$PN"102"80;
"DQ0_B"
$PN"100"79;
"HAS"
$PN"148"20;
"HSCL"
$PN"4"16;
"HSDA"
$PN"5"19;
"LBD||RSP_A_N"
$PN"86"78;
"LBS||RSP_B_N"
$PN"87"77;
"PAR_A"
$PN"74"72;
"PAR_B"
$PN"227"71;
"RESET_N \B"
$PN"207"168;
"RFU6"
$PN"232"0;
"RFU5"
$PN"231"0;
"RFU4"
$PN"220"0;
"RFU3"
$PN"150"0;
"RFU2"
$PN"149"0;
"RFU1"
$PN"144"0;
"RFU0"
$PN"2"0;
"VIN_MGMT"
$PN"3"21;
%"SCONN288_DDR506112002KQ"
"3","(-1325,3950)","0","pure_quanta","I352";
;
LOCATION"J23"
$SEC"3"
CDS_SEC"3"
MATERIAL"IO"
PART_TYPE"SMLF"
VALUE"SCONN288_DDR506112002KQ"
CDS_LIB"pure_quanta"
NEEDS_NO_SIZE"TRUE"
CDS_LMAN_SYM_OUTLINE"-450,1800,450,-1750"
PART_NUMBER"DFHST8FS479";
"G3"
$PN"G3"170;
"G2"
$PN"G2"170;
"G1"
$PN"G1"170;
"VSS62"
$PN"141"170;
"VSS61"
$PN"139"170;
"VSS60"
$PN"136"170;
"VSS58"
$PN"132"170;
"VSS104"
$PN"240"169;
"VSS102"
$PN"235"169;
"VSS100"
$PN"230"169;
"VIN_BULK2"
$PN"146"172;
"VIN_BULK1"
$PN"145"172;
"VIN_BULK0"
$PN"1"172;
"VSS126"
$PN"288"169;
"VSS125"
$PN"286"169;
"VSS124"
$PN"284"169;
"VSS123"
$PN"281"169;
"VSS122"
$PN"279"169;
"VSS121"
$PN"277"169;
"VSS120"
$PN"275"169;
"VSS119"
$PN"273"169;
"VSS118"
$PN"270"169;
"VSS117"
$PN"268"169;
"VSS116"
$PN"266"169;
"VSS115"
$PN"264"169;
"VSS114"
$PN"262"169;
"VSS113"
$PN"259"169;
"VSS112"
$PN"257"169;
"VSS111"
$PN"255"169;
"VSS110"
$PN"253"169;
"VSS109"
$PN"251"169;
"VSS108"
$PN"248"169;
"VSS107"
$PN"246"169;
"VSS106"
$PN"244"169;
"VSS105"
$PN"242"169;
"VSS103"
$PN"237"169;
"VSS101"
$PN"233"169;
"VSS99"
$PN"228"169;
"VSS98"
$PN"226"169;
"VSS97"
$PN"224"169;
"VSS96"
$PN"222"169;
"VSS95"
$PN"219"169;
"VSS94"
$PN"216"169;
"VSS93"
$PN"214"169;
"VSS92"
$PN"212"169;
"VSS91"
$PN"210"169;
"VSS90"
$PN"208"169;
"VSS89"
$PN"206"169;
"VSS88"
$PN"204"169;
"VSS87"
$PN"202"169;
"VSS86"
$PN"199"169;
"VSS85"
$PN"197"169;
"VSS84"
$PN"195"169;
"VSS83"
$PN"193"169;
"VSS82"
$PN"191"169;
"VSS81"
$PN"188"169;
"VSS80"
$PN"186"169;
"VSS79"
$PN"184"169;
"VSS78"
$PN"182"169;
"VSS77"
$PN"180"169;
"VSS76"
$PN"177"169;
"VSS75"
$PN"175"169;
"VSS74"
$PN"173"169;
"VSS73"
$PN"171"169;
"VSS72"
$PN"169"169;
"VSS71"
$PN"166"169;
"VSS70"
$PN"164"169;
"VSS69"
$PN"162"169;
"VSS68"
$PN"160"169;
"VSS67"
$PN"158"169;
"VSS66"
$PN"155"169;
"VSS65"
$PN"153"169;
"VSS64"
$PN"151"169;
"VSS63"
$PN"143"170;
"VSS59"
$PN"134"170;
"VSS57"
$PN"130"170;
"VSS56"
$PN"128"170;
"VSS55"
$PN"125"170;
"VSS54"
$PN"123"170;
"VSS53"
$PN"121"170;
"VSS52"
$PN"119"170;
"VSS51"
$PN"117"170;
"VSS50"
$PN"114"170;
"VSS49"
$PN"112"170;
"VSS48"
$PN"110"170;
"VSS47"
$PN"108"170;
"VSS46"
$PN"106"170;
"VSS45"
$PN"103"170;
"VSS44"
$PN"101"170;
"VSS43"
$PN"99"170;
"VSS42"
$PN"97"170;
"VSS41"
$PN"95"170;
"VSS40"
$PN"92"170;
"VSS39"
$PN"90"170;
"VSS38"
$PN"88"170;
"VSS37"
$PN"85"170;
"VSS36"
$PN"83"170;
"VSS35"
$PN"81"170;
"VSS34"
$PN"79"170;
"VSS33"
$PN"77"170;
"VSS32"
$PN"75"170;
"VSS31"
$PN"73"170;
"VSS30"
$PN"71"170;
"VSS29"
$PN"69"170;
"VSS28"
$PN"67"170;
"VSS27"
$PN"65"170;
"VSS26"
$PN"63"170;
"VSS25"
$PN"61"170;
"VSS24"
$PN"59"170;
"VSS23"
$PN"57"170;
"VSS22"
$PN"54"170;
"VSS21"
$PN"52"170;
"VSS20"
$PN"50"170;
"VSS19"
$PN"48"170;
"VSS18"
$PN"46"170;
"VSS17"
$PN"43"170;
"VSS16"
$PN"41"170;
"VSS15"
$PN"39"170;
"VSS14"
$PN"37"170;
"VSS13"
$PN"35"170;
"VSS12"
$PN"32"170;
"VSS11"
$PN"30"170;
"VSS10"
$PN"28"170;
"VSS9"
$PN"26"170;
"VSS8"
$PN"24"170;
"VSS7"
$PN"21"170;
"VSS6"
$PN"19"170;
"VSS5"
$PN"17"170;
"VSS4"
$PN"15"170;
"VSS3"
$PN"13"170;
"VSS2"
$PN"10"170;
"VSS1"
$PN"8"170;
"VSS0"
$PN"6"170;
%"Q_CAP"
"1","(-8650,3575)","2","pure_quanta","I361";
;
LOCATION"C108"
$SEC"1"
CDS_SEC"1"
VALUE"0.1UF"
MATERIAL"X7R"
PACK_TYPE"0402"
TOLERANCE"10%"
VOLTAGE"25V"
CDS_LIB"pure_quanta"
BOM_COST"MEM"
ROOM""
PART_NUMBER"CH4104K1B00";
"B"
$PN"2"2;
"A"
$PN"1"21;
%"GND"
"1","(-8650,3350)","0","mstr_symbols","I362";
;
ROOM"MEM_EFGH_DECOUPLING_CAPS"
VOLTAGE"0"
BOM_COST"MEM"
SIZE"1B"
CDS_LIB"mstr_symbols"
BODY_TYPE"PLUMBING"
HDL_POWER"GND";
"A\NAC"2;
%"Q_RES"
"1","(-8550,2475)","2","pure_quanta","I364";
;
LOCATION"R296"
$SEC"1"
CDS_SEC"1"
VALUE"1K"
PACK_TYPE"0402LF"
MATERIAL"CHIP"
WATTAGE"1/16W"
BOM_COST"MEM"
CDS_LIB"pure_quanta"
TOLERANCE"1%"
ROOM""
PART_NUMBER"CS21002FB06";
"B"
$PN"2"24;
"A"
$PN"1"17;
%"Q_RES"
"2","(-8425,2625)","0","pure_quanta","I365";
;
LOCATION"R94"
$SEC"1"
CDS_SEC"1"
VALUE"1K"
TOLERANCE"1%"
WATTAGE"1/16W"
PACK_TYPE"0402LF"
MATERIAL"EMPTY"
BOM_COST"MEM"
CDS_LIB"pure_quanta"
ROOM""
PART_NUMBER"CS21002FB06";
"A"
$PN"1"3;
"B"
$PN"2"17;
%"VCC_CORE"
"1","(-8425,2800)","0","mstr_symbols","I366";
;
HDL_POWER"P3V3"
ROOM"PVCCINFAON_CPU0_CTRL"
VOLTAGE"3.3"
CDS_LIB"mstr_symbols";
"A"3;
%"TAP"
"1","(-3375,4775)","0","mstr_standard","I372";
;
CDS_LIB"mstr_standard"
BODY_TYPE"PLUMBING"
HDL_TAP"TRUE";
"B \NAC \NWC"10;
"S \NAC"
BN"9"33;
%"TAP"
"1","(-3375,4675)","0","mstr_standard","I373";
;
CDS_LIB"mstr_standard"
BODY_TYPE"PLUMBING"
HDL_TAP"TRUE";
"B \NAC \NWC"10;
"S \NAC"
BN"8"35;
%"TAP"
"1","(-3375,4475)","0","mstr_standard","I374";
;
CDS_LIB"mstr_standard"
BODY_TYPE"PLUMBING"
HDL_TAP"TRUE";
"B \NAC \NWC"10;
"S \NAC"
BN"6"40;
%"TAP"
"1","(-3375,4575)","0","mstr_standard","I375";
;
CDS_LIB"mstr_standard"
BODY_TYPE"PLUMBING"
HDL_TAP"TRUE";
"B \NAC \NWC"10;
"S \NAC"
BN"7"69;
%"TAP"
"1","(-3375,4375)","0","mstr_standard","I376";
;
CDS_LIB"mstr_standard"
BODY_TYPE"PLUMBING"
HDL_TAP"TRUE";
"B \NAC \NWC"10;
"S \NAC"
BN"5"44;
%"TAP"
"1","(-3575,4725)","0","mstr_standard","I377";
;
CDS_LIB"mstr_standard"
BODY_TYPE"PLUMBING"
HDL_TAP"TRUE";
"B \NAC \NWC"11;
"S \NAC"
BN"8"34;
%"TAP"
"1","(-3575,4825)","0","mstr_standard","I378";
;
CDS_LIB"mstr_standard"
BODY_TYPE"PLUMBING"
HDL_TAP"TRUE";
"B \NAC \NWC"11;
"S \NAC"
BN"9"32;
%"TAP"
"1","(-3575,4625)","0","mstr_standard","I379";
;
CDS_LIB"mstr_standard"
BODY_TYPE"PLUMBING"
HDL_TAP"TRUE";
"B \NAC \NWC"11;
"S \NAC"
BN"7"37;
%"TAP"
"1","(-3575,4525)","0","mstr_standard","I380";
;
CDS_LIB"mstr_standard"
BODY_TYPE"PLUMBING"
HDL_TAP"TRUE";
"B \NAC \NWC"11;
"S \NAC"
BN"6"68;
%"TAP"
"1","(-3575,4425)","0","mstr_standard","I381";
;
CDS_LIB"mstr_standard"
BODY_TYPE"PLUMBING"
HDL_TAP"TRUE";
"B \NAC \NWC"11;
"S \NAC"
BN"5"43;
%"TAP"
"1","(-3375,4275)","0","mstr_standard","I382";
;
CDS_LIB"mstr_standard"
BODY_TYPE"PLUMBING"
HDL_TAP"TRUE";
"B \NAC \NWC"10;
"S \NAC"
BN"4"48;
%"TAP"
"1","(-3375,4175)","0","mstr_standard","I383";
;
CDS_LIB"mstr_standard"
BODY_TYPE"PLUMBING"
HDL_TAP"TRUE";
"B \NAC \NWC"10;
"S \NAC"
BN"3"52;
%"TAP"
"1","(-3375,4075)","0","mstr_standard","I384";
;
CDS_LIB"mstr_standard"
BODY_TYPE"PLUMBING"
HDL_TAP"TRUE";
"B \NAC \NWC"10;
"S \NAC"
BN"2"56;
%"TAP"
"1","(-3375,3975)","0","mstr_standard","I385";
;
CDS_LIB"mstr_standard"
BODY_TYPE"PLUMBING"
HDL_TAP"TRUE";
"B \NAC \NWC"10;
"S \NAC"
BN"1"60;
%"TAP"
"1","(-3375,3875)","0","mstr_standard","I386";
;
CDS_LIB"mstr_standard"
BODY_TYPE"PLUMBING"
HDL_TAP"TRUE";
"B \NAC \NWC"10;
"S \NAC"
BN"0"64;
%"TAP"
"1","(-3575,4225)","0","mstr_standard","I387";
;
CDS_LIB"mstr_standard"
BODY_TYPE"PLUMBING"
HDL_TAP"TRUE";
"B \NAC \NWC"11;
"S \NAC"
BN"3"51;
%"TAP"
"1","(-3575,4325)","0","mstr_standard","I388";
;
CDS_LIB"mstr_standard"
BODY_TYPE"PLUMBING"
HDL_TAP"TRUE";
"B \NAC \NWC"11;
"S \NAC"
BN"4"47;
%"TAP"
"1","(-3575,4125)","0","mstr_standard","I389";
;
CDS_LIB"mstr_standard"
BODY_TYPE"PLUMBING"
HDL_TAP"TRUE";
"B \NAC \NWC"11;
"S \NAC"
BN"2"55;
%"TAP"
"1","(-3575,4025)","0","mstr_standard","I390";
;
CDS_LIB"mstr_standard"
BODY_TYPE"PLUMBING"
HDL_TAP"TRUE";
"B \NAC \NWC"11;
"S \NAC"
BN"1"59;
%"TAP"
"1","(-3575,3925)","0","mstr_standard","I391";
;
CDS_LIB"mstr_standard"
BODY_TYPE"PLUMBING"
HDL_TAP"TRUE";
"B \NAC \NWC"11;
"S \NAC"
BN"0"63;
%"TAP"
"1","(-3375,3725)","0","mstr_standard","I392";
;
CDS_LIB"mstr_standard"
BODY_TYPE"PLUMBING"
HDL_TAP"TRUE";
"B \NAC \NWC"13;
"S \NAC"
BN"9"31;
%"TAP"
"1","(-3375,3625)","0","mstr_standard","I393";
;
CDS_LIB"mstr_standard"
BODY_TYPE"PLUMBING"
HDL_TAP"TRUE";
"B \NAC \NWC"13;
"S \NAC"
BN"8"66;
%"TAP"
"1","(-3375,3525)","0","mstr_standard","I394";
;
CDS_LIB"mstr_standard"
BODY_TYPE"PLUMBING"
HDL_TAP"TRUE";
"B \NAC \NWC"13;
"S \NAC"
BN"7"36;
%"TAP"
"1","(-3375,3325)","0","mstr_standard","I395";
;
CDS_LIB"mstr_standard"
BODY_TYPE"PLUMBING"
HDL_TAP"TRUE";
"B \NAC \NWC"13;
"S \NAC"
BN"5"42;
%"TAP"
"1","(-3375,3425)","0","mstr_standard","I396";
;
CDS_LIB"mstr_standard"
BODY_TYPE"PLUMBING"
HDL_TAP"TRUE";
"B \NAC \NWC"13;
"S \NAC"
BN"6"39;
%"TAP"
"1","(-3575,3675)","0","mstr_standard","I397";
;
CDS_LIB"mstr_standard"
BODY_TYPE"PLUMBING"
HDL_TAP"TRUE";
"B \NAC \NWC"12;
"S \NAC"
BN"8"67;
%"TAP"
"1","(-3575,3775)","0","mstr_standard","I398";
;
CDS_LIB"mstr_standard"
BODY_TYPE"PLUMBING"
HDL_TAP"TRUE";
"B \NAC \NWC"12;
"S \NAC"
BN"9"30;
%"TAP"
"1","(-3575,3575)","0","mstr_standard","I399";
;
CDS_LIB"mstr_standard"
BODY_TYPE"PLUMBING"
HDL_TAP"TRUE";
"B \NAC \NWC"12;
"S \NAC"
BN"7"65;
%"TAP"
"1","(-3575,3475)","0","mstr_standard","I400";
;
CDS_LIB"mstr_standard"
BODY_TYPE"PLUMBING"
HDL_TAP"TRUE";
"B \NAC \NWC"12;
"S \NAC"
BN"6"38;
%"TAP"
"1","(-3575,3375)","0","mstr_standard","I401";
;
CDS_LIB"mstr_standard"
BODY_TYPE"PLUMBING"
HDL_TAP"TRUE";
"B \NAC \NWC"12;
"S \NAC"
BN"5"41;
%"TAP"
"1","(-3375,3225)","0","mstr_standard","I402";
;
CDS_LIB"mstr_standard"
BODY_TYPE"PLUMBING"
HDL_TAP"TRUE";
"B \NAC \NWC"13;
"S \NAC"
BN"4"46;
%"TAP"
"1","(-3375,3125)","0","mstr_standard","I403";
;
CDS_LIB"mstr_standard"
BODY_TYPE"PLUMBING"
HDL_TAP"TRUE";
"B \NAC \NWC"13;
"S \NAC"
BN"3"50;
%"TAP"
"1","(-3375,3025)","0","mstr_standard","I404";
;
CDS_LIB"mstr_standard"
BODY_TYPE"PLUMBING"
HDL_TAP"TRUE";
"B \NAC \NWC"13;
"S \NAC"
BN"2"54;
%"TAP"
"1","(-3375,2825)","0","mstr_standard","I405";
;
CDS_LIB"mstr_standard"
BODY_TYPE"PLUMBING"
HDL_TAP"TRUE";
"B \NAC \NWC"13;
"S \NAC"
BN"0"62;
%"TAP"
"1","(-3375,2925)","0","mstr_standard","I406";
;
CDS_LIB"mstr_standard"
BODY_TYPE"PLUMBING"
HDL_TAP"TRUE";
"B \NAC \NWC"13;
"S \NAC"
BN"1"58;
%"TAP"
"1","(-3575,3175)","0","mstr_standard","I407";
;
CDS_LIB"mstr_standard"
BODY_TYPE"PLUMBING"
HDL_TAP"TRUE";
"B \NAC \NWC"12;
"S \NAC"
BN"3"49;
%"TAP"
"1","(-3575,3275)","0","mstr_standard","I408";
;
CDS_LIB"mstr_standard"
BODY_TYPE"PLUMBING"
HDL_TAP"TRUE";
"B \NAC \NWC"12;
"S \NAC"
BN"4"45;
%"TAP"
"1","(-3575,3075)","0","mstr_standard","I409";
;
CDS_LIB"mstr_standard"
BODY_TYPE"PLUMBING"
HDL_TAP"TRUE";
"B \NAC \NWC"12;
"S \NAC"
BN"2"53;
%"TAP"
"1","(-3575,2975)","0","mstr_standard","I410";
;
CDS_LIB"mstr_standard"
BODY_TYPE"PLUMBING"
HDL_TAP"TRUE";
"B \NAC \NWC"12;
"S \NAC"
BN"1"57;
%"TAP"
"1","(-3575,2875)","0","mstr_standard","I411";
;
CDS_LIB"mstr_standard"
BODY_TYPE"PLUMBING"
HDL_TAP"TRUE";
"B \NAC \NWC"12;
"S \NAC"
BN"0"61;
%"SCONN288_DDR506112002KQ"
"2","(-4525,3825)","0","pure_quanta","I412";
;
LOCATION"J23"
$SEC"2"
CDS_SEC"2"
PART_TYPE"SMLF"
VALUE"SCONN288_DDR506112002KQ"
MATERIAL"IO"
CDS_LIB"pure_quanta"
NEEDS_NO_SIZE"TRUE"
CDS_LMAN_SYM_OUTLINE"-600,1150,600,-1150"
PART_NUMBER"DFHST8FS479";
"DQS7_A_C||TDQS7_A_C \B"
$PN"178"69;
"DQS6_A_T||TDQS6_A_T"
$PN"168"68;
"DQS8_B_T||TDQS8_B_T"
$PN"283"67;
"DQS8_B_C||TDQS8_B_C \B"
$PN"282"66;
"DQS7_B_T||TDQS7_B_T"
$PN"272"65;
"DQS0_A_C \B"
$PN"12"64;
"DQS0_A_T"
$PN"11"63;
"DQS0_B_C \B"
$PN"105"62;
"DQS0_B_T"
$PN"104"61;
"DQS1_A_C \B"
$PN"23"60;
"DQS1_A_T"
$PN"22"59;
"DQS1_B_C \B"
$PN"116"58;
"DQS1_B_T"
$PN"115"57;
"DQS2_A_C \B"
$PN"34"56;
"DQS2_A_T"
$PN"33"55;
"DQS2_B_C \B"
$PN"127"54;
"DQS2_B_T"
$PN"126"53;
"DQS3_A_C \B"
$PN"45"52;
"DQS3_A_T"
$PN"44"51;
"DQS3_B_C \B"
$PN"138"50;
"DQS3_B_T"
$PN"137"49;
"DQS4_A_C \B"
$PN"56"48;
"DQS4_A_T"
$PN"55"47;
"DQS4_B_C \B"
$PN"238"46;
"DQS4_B_T"
$PN"239"45;
"DQS5_A_C||TDQS5_A_C||DQS5_A_T||TDQS5_A_T \B"
$PN"156"44;
"DQS5_A_T||TDQS5_A_T"
$PN"157"43;
"DQS5_B_C||TDQS5_B_C \B"
$PN"249"42;
"DQS5_B_T||TDQS5_B_T"
$PN"250"41;
"DQS6_A_C||TDQS6_A_C||DQS6_A_T||TDQS6_A_T \B"
$PN"167"40;
"DQS6_B_C||TDQS6_B_C \B"
$PN"260"39;
"DQS6_B_T||TDQS6_B_T"
$PN"261"38;
"DQS7_A_T||TDQS7_A_T"
$PN"179"37;
"DQS7_B_C||TDQS7_B_C \B"
$PN"271"36;
"DQS8_A_C||TDQS8_A_C \B"
$PN"189"35;
"DQS8_A_T||TDQS8_A_T"
$PN"190"34;
"DQS9_A_C||TDQS9_A_C \B"
$PN"200"33;
"DQS9_A_T||TDQS9_A_T"
$PN"201"32;
"DQS9_B_C||TDQS9_B_C \B"
$PN"94"31;
"DQS9_B_T||TDQS9_B_T||DBI4_B_N"
$PN"93"30;
%"GND"
"1","(-2925,5800)","0","pure_quanta_power","I413";
;
ROOM"MEM_EFGH_DECOUPLING_CAPS"
CDS_LIB"pure_quanta_power"
BOM_COST"MEM"
SIZE"1B"
HDL_POWER"GND";
"A<SIZE-1..0>\NAC"171;
%"Q_CAP"
"1","(-2925,6150)","2","pure_quanta","I414";
;
LOCATION"C154"
$SEC"1"
CDS_SEC"1"
MATERIAL"X6S"
VALUE"10UF"
PACK_TYPE"C0805"
TOLERANCE"10%"
VOLTAGE"25V"
CDS_LIB"pure_quanta"
BOM_COST"MEM"
ROOM""
PART_NUMBER"CH6104KEA00";
"B"
$PN"2"171;
"A"
$PN"1"172;
%"Q_CAP"
"1","(-2350,6150)","2","pure_quanta","I415";
;
LOCATION"C155"
$SEC"1"
CDS_SEC"1"
MATERIAL"X6S"
TOLERANCE"10%"
VALUE"10UF"
PACK_TYPE"C0805"
VOLTAGE"25V"
CDS_LIB"pure_quanta"
BOM_COST"MEM"
ROOM""
PART_NUMBER"CH6104KEA00";
"B"
$PN"2"171;
"A"
$PN"1"172;
%"UNIVERSAL_POWER"
"1","(-2925,6475)","0","pure_quanta_power","I416";
;
HDL_POWER"P12V_MEM_CPU0"
CDS_LIB"pure_quanta_power"
BOM_COST"VR_SYSTEM";
"A"172;
%"Q_RES"
"1","(-7825,2975)","0","pure_quanta","I418";
;
LOCATION"R1573"
$SEC"1"
CDS_SEC"1"
VALUE"49.9"
CDS_LIB"pure_quanta"
TOLERANCE"1%"
WATTAGE"1/16W"
PACK_TYPE"0402LF"
MATERIAL"CHIP"
PART_NUMBER"CS04992FB07";
"B"
$PN"2"16;
"A"
$PN"1"15;
%"Q_RES"
"1","(-8125,3175)","0","pure_quanta","I419";
;
LOCATION"R1679"
$SEC"1"
CDS_SEC"1"
MATERIAL"CHIP"
PACK_TYPE"0402LF"
VALUE"10"
TOLERANCE"1%"
WATTAGE"1/16W"
CDS_LIB"pure_quanta"
PART_NUMBER"CS01002FB07";
"B"
$PN"2"19;
"A"
$PN"1"18;
END.
